(kicad_pcb
	(version 20260206)
	(generator "pcbnew")
	(generator_version "10.0")
	(general
		(thickness 1.6)
		(legacy_teardrops no)
	)
	(paper "A4")
	(title_block
		(title "Wiwynn_Tioga_Pass_MB.brd")
		(comment 1 "Tioga Pass / footprint 2254 of 4770 (U5D1), pads 3152-3263 of 3647")
	)
	(layers
		(0 "F.Cu" signal "TOP")
		(4 "In1.Cu" signal "L2GND")
		(6 "In2.Cu" signal "L3")
		(8 "In3.Cu" signal "L4GND")
		(10 "In4.Cu" signal "L5")
		(12 "In5.Cu" signal "L6GND")
		(14 "In6.Cu" signal "L7VCC")
		(16 "In7.Cu" signal "L8VCC")
		(18 "In8.Cu" signal "L9GND")
		(20 "In9.Cu" signal "L10")
		(22 "In10.Cu" signal "L11GND")
		(24 "In11.Cu" signal "L12")
		(26 "In12.Cu" signal "L13GND")
		(2 "B.Cu" signal "BOTTOM")
		(9 "F.Adhes" user "F.Adhesive")
		(11 "B.Adhes" user "B.Adhesive")
		(13 "F.Paste" user "Package Geometry/Pastemask Top")
		(15 "B.Paste" user "Package Geometry/Pastemask Bottom")
		(5 "F.SilkS" user "Ref Des/Silkscreen Top")
		(7 "B.SilkS" user "Ref Des/Silkscreen Bottom")
		(1 "F.Mask" user "Board Geometry/Soldermask Top")
		(3 "B.Mask" user "Board Geometry/Soldermask Bottom")
		(17 "Dwgs.User" user "User.Drawings")
		(19 "Cmts.User" user "User.Comments")
		(21 "Eco1.User" user "User.Eco1")
		(23 "Eco2.User" user "User.Eco2")
		(25 "Edge.Cuts" user "Board Geometry/Outline")
		(27 "Margin" user)
		(31 "F.CrtYd" user "Package Geometry/Place Bound Top")
		(29 "B.CrtYd" user "Package Geometry/Place Bound Bottom")
		(35 "F.Fab" user "Ref Des/Assembly Top")
		(33 "B.Fab" user "Ref Des/Assembly Bottom")
	)
	(footprint ""
		(layer "F.Cu")
		(at 270.000222 -76.550012 180)
		(property "Reference" "U5D1"
			(at 19.124422 31.601918 0)
			(unlocked yes)
			(layer "F.SilkS")
			(effects
				(font
					(size 0.7874 0.5842)
					(thickness 0.1524)
				)
			)
		)
		(property "Value" ""
			(at 0 0 180)
			(layer "F.Fab")
			(effects
				(font
					(size 1.27 1.27)
				)
			)
		)
		(duplicate_pad_numbers_are_jumpers no)
		(pad "J30" smd circle
			(at -12.354052 -21.140674)
			(size 0.4318 0.4318)
			(layers "F.Cu" "F.Mask" "F.Paste")
			(net "M_A_DQS_DN<15>")
		)
		(pad "J32" smd circle
			(at -10.637012 -21.140674)
			(size 0.4318 0.4318)
			(layers "F.Cu" "F.Mask" "F.Paste")
			(net "GND")
		)
		(pad "J34" smd circle
			(at -8.919972 -21.140674)
			(size 0.4318 0.4318)
			(layers "F.Cu" "F.Mask" "F.Paste")
			(net "GND")
		)
		(pad "J36" smd circle
			(at -7.202932 -21.140674)
			(size 0.4318 0.4318)
			(layers "F.Cu" "F.Mask" "F.Paste")
			(net "M_A_DQS_DN<14>")
		)
		(pad "J38" smd circle
			(at -5.485892 -21.140674)
			(size 0.4318 0.4318)
			(layers "F.Cu" "F.Mask" "F.Paste")
			(net "GND")
		)
		(pad "J40" smd circle
			(at -3.769106 -21.140674)
			(size 0.4318 0.4318)
			(layers "F.Cu" "F.Mask" "F.Paste")
			(net "GND")
		)
		(pad "J42" smd circle
			(at -2.052066 -21.140674)
			(size 0.4318 0.4318)
			(layers "F.Cu" "F.Mask" "F.Paste")
			(net "M_B_DQS_DN<13>")
		)
		(pad "J46" smd circle
			(at 2.910586 -22.940772)
			(size 0.4318 0.4318)
			(layers "F.Cu" "F.Mask" "F.Paste")
			(net "TP_CPU0_RSVD_269")
		)
		(pad "J48" smd circle
			(at 4.627626 -22.940772)
			(size 0.4318 0.4318)
			(layers "F.Cu" "F.Mask" "F.Paste")
			(net "M_A_MA<13>")
		)
		(pad "J50" smd circle
			(at 6.344412 -22.940772)
			(size 0.4318 0.4318)
			(layers "F.Cu" "F.Mask" "F.Paste")
			(net "M_B_CS_N<4>")
		)
		(pad "J52" smd circle
			(at 8.061452 -22.940772)
			(size 0.4318 0.4318)
			(layers "F.Cu" "F.Mask" "F.Paste")
			(net "M_B_MA<0>")
		)
		(pad "J54" smd circle
			(at 9.778492 -22.940772)
			(size 0.4318 0.4318)
			(layers "F.Cu" "F.Mask" "F.Paste")
			(net "M_A_MA<10>")
		)
		(pad "J56" smd circle
			(at 11.495532 -22.940772)
			(size 0.4318 0.4318)
			(layers "F.Cu" "F.Mask" "F.Paste")
			(net "M_A_CLK_DN<2>")
		)
		(pad "J58" smd circle
			(at 13.212572 -22.940772)
			(size 0.4318 0.4318)
			(layers "F.Cu" "F.Mask" "F.Paste")
			(net "M_B_MA<1>")
		)
		(pad "J60" smd circle
			(at 14.929612 -22.940772)
			(size 0.4318 0.4318)
			(layers "F.Cu" "F.Mask" "F.Paste")
			(net "M_A_ACT_N")
		)
		(pad "J62" smd circle
			(at 16.646398 -22.940772)
			(size 0.4318 0.4318)
			(layers "F.Cu" "F.Mask" "F.Paste")
			(net "TP_CPU0_RSVD_268")
		)
		(pad "J64" smd circle
			(at 18.363438 -22.940772)
			(size 0.4318 0.4318)
			(layers "F.Cu" "F.Mask" "F.Paste")
			(net "M_A_MA<12>")
		)
		(pad "J66" smd circle
			(at 20.080478 -22.940772)
			(size 0.4318 0.4318)
			(layers "F.Cu" "F.Mask" "F.Paste")
			(net "M_B_ECC<2>")
		)
		(pad "J68" smd circle
			(at 21.797518 -22.940772)
			(size 0.4318 0.4318)
			(layers "F.Cu" "F.Mask" "F.Paste")
			(net "M_B_DQS_DP<17>")
		)
		(pad "J70" smd circle
			(at 23.514558 -22.940772)
			(size 0.4318 0.4318)
			(layers "F.Cu" "F.Mask" "F.Paste")
			(net "M_B_ECC<0>")
		)
		(pad "J72" smd circle
			(at 25.231598 -22.940772)
			(size 0.4318 0.4318)
			(layers "F.Cu" "F.Mask" "F.Paste")
			(net "GND")
		)
		(pad "J74" smd circle
			(at 26.948384 -22.940772)
			(size 0.4318 0.4318)
			(layers "F.Cu" "F.Mask" "F.Paste")
			(net "GND")
		)
		(pad "J76" smd circle
			(at 28.665424 -22.940772)
			(size 0.4318 0.4318)
			(layers "F.Cu" "F.Mask" "F.Paste")
			(net "GND")
		)
		(pad "J78" smd circle
			(at 30.382464 -22.940772)
			(size 0.4318 0.4318)
			(layers "F.Cu" "F.Mask" "F.Paste")
			(net "M_B_DQ<23>")
		)
		(pad "J80" smd circle
			(at 32.099504 -22.940772)
			(size 0.4318 0.4318)
			(layers "F.Cu" "F.Mask" "F.Paste")
			(net "M_B_DQ<17>")
		)
		(pad "J82" smd circle
			(at 33.816544 -22.940772)
			(size 0.4318 0.4318)
			(layers "F.Cu" "F.Mask" "F.Paste")
			(net "GND")
		)
		(pad "J84" smd circle
			(at 35.533584 -22.940772)
			(size 0.4318 0.4318)
			(layers "F.Cu" "F.Mask" "F.Paste")
			(net "GND")
		)
		(pad "J86" smd custom
			(at 37.250624 -22.940772 270)
			(size 0.10795 0.10795)
			(layers "F.Cu" "F.Mask" "F.Paste")
			(net "GND")
			(options
				(clearance outline)
				(anchor circle)
			)
			(primitives
				(gr_poly
					(pts
						(arc
							(start 0.2159 -0.0381)
							(mid 0 -0.254)
							(end -0.2159 -0.0381)
						)
						(arc
							(start -0.2159 0.0381)
							(mid 0 0.254)
							(end 0.2159 0.0381)
						)
					)
					(width 0)
					(fill yes)
				)
			)
		)
		(pad "K1" smd custom
			(at -37.250624 -20.645628 90)
			(size 0.10795 0.10795)
			(layers "F.Cu" "F.Mask" "F.Paste")
			(net "GND")
			(options
				(clearance outline)
				(anchor circle)
			)
			(primitives
				(gr_poly
					(pts
						(arc
							(start 0.2159 -0.0381)
							(mid 0 -0.254)
							(end -0.2159 -0.0381)
						)
						(arc
							(start -0.2159 0.0381)
							(mid 0 0.254)
							(end 0.2159 0.0381)
						)
					)
					(width 0)
					(fill yes)
				)
			)
		)
		(pad "K3" smd circle
			(at -35.533584 -20.645628)
			(size 0.4318 0.4318)
			(layers "F.Cu" "F.Mask" "F.Paste")
			(net "UPI_CPU0_CPU1_P1P1_DP<18>")
		)
		(pad "K5" smd circle
			(at -33.816544 -20.645628)
			(size 0.4318 0.4318)
			(layers "F.Cu" "F.Mask" "F.Paste")
			(net "UPI_CPU0_CPU1_P1P1_DN<17>")
		)
		(pad "K7" smd circle
			(at -32.099504 -20.645628)
			(size 0.4318 0.4318)
			(layers "F.Cu" "F.Mask" "F.Paste")
			(net "UPI_CPU0_CPU1_P1P1_DP<14>")
		)
		(pad "K9" smd circle
			(at -30.382464 -20.645628)
			(size 0.4318 0.4318)
			(layers "F.Cu" "F.Mask" "F.Paste")
			(net "UPI_CPU0_CPU1_P1P1_DN<13>")
		)
		(pad "K11" smd circle
			(at -28.665424 -20.645628)
			(size 0.4318 0.4318)
			(layers "F.Cu" "F.Mask" "F.Paste")
			(net "GND")
		)
		(pad "K13" smd circle
			(at -26.948384 -20.645628)
			(size 0.4318 0.4318)
			(layers "F.Cu" "F.Mask" "F.Paste")
			(net "GND")
		)
		(pad "K15" smd circle
			(at -25.231598 -20.645628)
			(size 0.4318 0.4318)
			(layers "F.Cu" "F.Mask" "F.Paste")
			(net "PVCCIO_CPU0")
		)
		(pad "K17" smd circle
			(at -23.514558 -20.645628)
			(size 0.4318 0.4318)
			(layers "F.Cu" "F.Mask" "F.Paste")
			(net "GND")
		)
		(pad "K19" smd circle
			(at -21.797518 -20.645628)
			(size 0.4318 0.4318)
			(layers "F.Cu" "F.Mask" "F.Paste")
			(net "UPI_CPU0_CPU1_P1P1_DN<4>")
		)
		(pad "K21" smd circle
			(at -20.080478 -20.645628)
			(size 0.4318 0.4318)
			(layers "F.Cu" "F.Mask" "F.Paste")
			(net "UPI_CPU0_CPU1_P1P1_DP<0>")
		)
		(pad "K23" smd circle
			(at -18.363438 -20.645628)
			(size 0.4318 0.4318)
			(layers "F.Cu" "F.Mask" "F.Paste")
			(net "M_A_DQ<63>")
		)
		(pad "K25" smd circle
			(at -16.646398 -20.645628)
			(size 0.4318 0.4318)
			(layers "F.Cu" "F.Mask" "F.Paste")
			(net "M_A_DQ<56>")
		)
		(pad "K27" smd circle
			(at -14.929612 -20.645628)
			(size 0.4318 0.4318)
			(layers "F.Cu" "F.Mask" "F.Paste")
			(net "GND")
		)
		(pad "K29" smd circle
			(at -13.212572 -20.645628)
			(size 0.4318 0.4318)
			(layers "F.Cu" "F.Mask" "F.Paste")
			(net "M_A_DQ<54>")
		)
		(pad "K31" smd circle
			(at -11.495532 -20.645628)
			(size 0.4318 0.4318)
			(layers "F.Cu" "F.Mask" "F.Paste")
			(net "M_A_DQ<48>")
		)
		(pad "K33" smd circle
			(at -9.778492 -20.645628)
			(size 0.4318 0.4318)
			(layers "F.Cu" "F.Mask" "F.Paste")
			(net "GND")
		)
		(pad "K35" smd circle
			(at -8.061452 -20.645628)
			(size 0.4318 0.4318)
			(layers "F.Cu" "F.Mask" "F.Paste")
			(net "M_A_DQ<46>")
		)
		(pad "K37" smd circle
			(at -6.344412 -20.645628)
			(size 0.4318 0.4318)
			(layers "F.Cu" "F.Mask" "F.Paste")
			(net "M_A_DQ<40>")
		)
		(pad "K39" smd circle
			(at -4.627626 -20.645628)
			(size 0.4318 0.4318)
			(layers "F.Cu" "F.Mask" "F.Paste")
			(net "GND")
		)
		(pad "K41" smd circle
			(at -2.910586 -20.645628)
			(size 0.4318 0.4318)
			(layers "F.Cu" "F.Mask" "F.Paste")
			(net "M_B_DQ<38>")
		)
		(pad "K43" smd circle
			(at -1.193546 -20.645628)
			(size 0.4318 0.4318)
			(layers "F.Cu" "F.Mask" "F.Paste")
			(net "M_B_DQ<32>")
		)
		(pad "K45" smd circle
			(at 2.052066 -22.445726)
			(size 0.508 0.508)
			(layers "F.Cu" "F.Mask" "F.Paste")
			(net "M_A_CS_N<7>")
		)
		(pad "K47" smd circle
			(at 3.769106 -22.445726)
			(size 0.4318 0.4318)
			(layers "F.Cu" "F.Mask" "F.Paste")
			(net "M_A_MA<17>")
		)
		(pad "K49" smd circle
			(at 5.485892 -22.445726)
			(size 0.4318 0.4318)
			(layers "F.Cu" "F.Mask" "F.Paste")
			(net "M_A_MA<15>")
		)
		(pad "K51" smd circle
			(at 7.202932 -22.445726)
			(size 0.4318 0.4318)
			(layers "F.Cu" "F.Mask" "F.Paste")
			(net "M_B_CS_N<0>")
		)
		(pad "K53" smd circle
			(at 8.919972 -22.445726)
			(size 0.4318 0.4318)
			(layers "F.Cu" "F.Mask" "F.Paste")
			(net "M_B_PAR")
		)
		(pad "K55" smd circle
			(at 10.637012 -22.445726)
			(size 0.4318 0.4318)
			(layers "F.Cu" "F.Mask" "F.Paste")
			(net "M_B_BA<1>")
		)
		(pad "K57" smd circle
			(at 12.354052 -22.445726)
			(size 0.4318 0.4318)
			(layers "F.Cu" "F.Mask" "F.Paste")
			(net "M_B_MA<2>")
		)
		(pad "K59" smd circle
			(at 14.071092 -22.445726)
			(size 0.4318 0.4318)
			(layers "F.Cu" "F.Mask" "F.Paste")
			(net "M_B_MA<9>")
		)
		(pad "K61" smd circle
			(at 15.787878 -22.445726)
			(size 0.4318 0.4318)
			(layers "F.Cu" "F.Mask" "F.Paste")
			(net "TP_CPU0_RSVD_267")
		)
		(pad "K63" smd circle
			(at 17.504918 -22.445726)
			(size 0.4318 0.4318)
			(layers "F.Cu" "F.Mask" "F.Paste")
			(net "M_B_CKE<2>")
		)
		(pad "K65" smd circle
			(at 19.221958 -22.445726)
			(size 0.4318 0.4318)
			(layers "F.Cu" "F.Mask" "F.Paste")
			(net "GND")
		)
		(pad "K67" smd circle
			(at 20.938998 -22.445726)
			(size 0.4318 0.4318)
			(layers "F.Cu" "F.Mask" "F.Paste")
			(net "GND")
		)
		(pad "K69" smd circle
			(at 22.656038 -22.445726)
			(size 0.4318 0.4318)
			(layers "F.Cu" "F.Mask" "F.Paste")
			(net "GND")
		)
		(pad "K71" smd circle
			(at 24.373078 -22.445726)
			(size 0.4318 0.4318)
			(layers "F.Cu" "F.Mask" "F.Paste")
			(net "GND")
		)
		(pad "K73" smd circle
			(at 26.090118 -22.445726)
			(size 0.4318 0.4318)
			(layers "F.Cu" "F.Mask" "F.Paste")
			(net "GND")
		)
		(pad "K75" smd circle
			(at 27.806904 -22.445726)
			(size 0.4318 0.4318)
			(layers "F.Cu" "F.Mask" "F.Paste")
			(net "M_A_DQS_DN<12>")
		)
		(pad "K77" smd circle
			(at 29.523944 -22.445726)
			(size 0.4318 0.4318)
			(layers "F.Cu" "F.Mask" "F.Paste")
			(net "GND")
		)
		(pad "K79" smd circle
			(at 31.240984 -22.445726)
			(size 0.4318 0.4318)
			(layers "F.Cu" "F.Mask" "F.Paste")
			(net "M_B_DQS_DN<2>")
		)
		(pad "K81" smd circle
			(at 32.958024 -22.445726)
			(size 0.4318 0.4318)
			(layers "F.Cu" "F.Mask" "F.Paste")
			(net "GND")
		)
		(pad "K83" smd circle
			(at 34.675064 -22.445726)
			(size 0.4318 0.4318)
			(layers "F.Cu" "F.Mask" "F.Paste")
			(net "GND")
		)
		(pad "K85" smd circle
			(at 36.392104 -22.445726)
			(size 0.4318 0.4318)
			(layers "F.Cu" "F.Mask" "F.Paste")
			(net "GND")
		)
		(pad "L2" smd circle
			(at -36.392104 -20.150074)
			(size 0.4318 0.4318)
			(layers "F.Cu" "F.Mask" "F.Paste")
			(net "GND")
		)
		(pad "L4" smd circle
			(at -34.675064 -20.150074)
			(size 0.4318 0.4318)
			(layers "F.Cu" "F.Mask" "F.Paste")
			(net "UPI_CPU0_CPU1_P1P1_DN<18>")
		)
		(pad "L6" smd circle
			(at -32.958024 -20.150074)
			(size 0.4318 0.4318)
			(layers "F.Cu" "F.Mask" "F.Paste")
			(net "GND")
		)
		(pad "L8" smd circle
			(at -31.240984 -20.150074)
			(size 0.4318 0.4318)
			(layers "F.Cu" "F.Mask" "F.Paste")
			(net "GND")
		)
		(pad "L10" smd circle
			(at -29.523944 -20.150074)
			(size 0.4318 0.4318)
			(layers "F.Cu" "F.Mask" "F.Paste")
			(net "GND")
		)
		(pad "L12" smd circle
			(at -27.806904 -20.150074)
			(size 0.4318 0.4318)
			(layers "F.Cu" "F.Mask" "F.Paste")
			(net "UPI_CPU1_CPU0_P1P1_DN<12>")
		)
		(pad "L14" smd circle
			(at -26.090118 -20.150074)
			(size 0.4318 0.4318)
			(layers "F.Cu" "F.Mask" "F.Paste")
			(net "PVCCIO_CPU0")
		)
		(pad "L16" smd circle
			(at -24.373078 -20.150074)
			(size 0.4318 0.4318)
			(layers "F.Cu" "F.Mask" "F.Paste")
			(net "PVCCIO_CPU0")
		)
		(pad "L18" smd circle
			(at -22.656038 -20.150074)
			(size 0.4318 0.4318)
			(layers "F.Cu" "F.Mask" "F.Paste")
			(net "UPI_CPU0_CPU1_P1P1_DP<4>")
		)
		(pad "L20" smd circle
			(at -20.938998 -20.150074)
			(size 0.4318 0.4318)
			(layers "F.Cu" "F.Mask" "F.Paste")
			(net "GND")
		)
		(pad "L22" smd circle
			(at -19.221958 -20.150074)
			(size 0.4318 0.4318)
			(layers "F.Cu" "F.Mask" "F.Paste")
			(net "GND")
		)
		(pad "L24" smd circle
			(at -17.504918 -20.150074)
			(size 0.4318 0.4318)
			(layers "F.Cu" "F.Mask" "F.Paste")
			(net "M_A_DQS_DP<16>")
		)
		(pad "L26" smd circle
			(at -15.787878 -20.150074)
			(size 0.4318 0.4318)
			(layers "F.Cu" "F.Mask" "F.Paste")
			(net "M_A_DQ<60>")
		)
		(pad "L28" smd circle
			(at -14.071092 -20.150074)
			(size 0.4318 0.4318)
			(layers "F.Cu" "F.Mask" "F.Paste")
			(net "M_A_DQ<50>")
		)
		(pad "L30" smd circle
			(at -12.354052 -20.150074)
			(size 0.4318 0.4318)
			(layers "F.Cu" "F.Mask" "F.Paste")
			(net "M_A_DQS_DP<15>")
		)
		(pad "L32" smd circle
			(at -10.637012 -20.150074)
			(size 0.4318 0.4318)
			(layers "F.Cu" "F.Mask" "F.Paste")
			(net "M_A_DQ<52>")
		)
		(pad "L34" smd circle
			(at -8.919972 -20.150074)
			(size 0.4318 0.4318)
			(layers "F.Cu" "F.Mask" "F.Paste")
			(net "M_A_DQ<42>")
		)
		(pad "L36" smd circle
			(at -7.202932 -20.150074)
			(size 0.4318 0.4318)
			(layers "F.Cu" "F.Mask" "F.Paste")
			(net "M_A_DQS_DP<14>")
		)
		(pad "L38" smd circle
			(at -5.485892 -20.150074)
			(size 0.4318 0.4318)
			(layers "F.Cu" "F.Mask" "F.Paste")
			(net "M_A_DQ<44>")
		)
		(pad "L40" smd circle
			(at -3.769106 -20.150074)
			(size 0.4318 0.4318)
			(layers "F.Cu" "F.Mask" "F.Paste")
			(net "M_B_DQ<34>")
		)
		(pad "L42" smd circle
			(at -2.052066 -20.150074)
			(size 0.4318 0.4318)
			(layers "F.Cu" "F.Mask" "F.Paste")
			(net "M_B_DQS_DP<13>")
		)
		(pad "L46" smd circle
			(at 2.910586 -21.950172)
			(size 0.4318 0.4318)
			(layers "F.Cu" "F.Mask" "F.Paste")
			(net "PVDDQ_ABC")
		)
		(pad "L48" smd circle
			(at 4.627626 -21.950172)
			(size 0.4318 0.4318)
			(layers "F.Cu" "F.Mask" "F.Paste")
			(net "PVDDQ_ABC")
		)
		(pad "L50" smd circle
			(at 6.344412 -21.950172)
			(size 0.4318 0.4318)
			(layers "F.Cu" "F.Mask" "F.Paste")
			(net "PVDDQ_ABC")
		)
		(pad "L52" smd circle
			(at 8.061452 -21.950172)
			(size 0.4318 0.4318)
			(layers "F.Cu" "F.Mask" "F.Paste")
			(net "PVDDQ_ABC")
		)
		(pad "L54" smd circle
			(at 9.778492 -21.950172)
			(size 0.4318 0.4318)
			(layers "F.Cu" "F.Mask" "F.Paste")
			(net "PVDDQ_ABC")
		)
		(pad "L56" smd circle
			(at 11.495532 -21.950172)
			(size 0.4318 0.4318)
			(layers "F.Cu" "F.Mask" "F.Paste")
			(net "PVDDQ_ABC")
		)
		(pad "L58" smd circle
			(at 13.212572 -21.950172)
			(size 0.4318 0.4318)
			(layers "F.Cu" "F.Mask" "F.Paste")
			(net "PVDDQ_ABC")
		)
		(pad "L60" smd circle
			(at 14.929612 -21.950172)
			(size 0.4318 0.4318)
			(layers "F.Cu" "F.Mask" "F.Paste")
			(net "PVDDQ_ABC")
		)
		(pad "L62" smd circle
			(at 16.646398 -21.950172)
			(size 0.4318 0.4318)
			(layers "F.Cu" "F.Mask" "F.Paste")
			(net "PVDDQ_ABC")
		)
		(pad "L64" smd circle
			(at 18.363438 -21.950172)
			(size 0.4318 0.4318)
			(layers "F.Cu" "F.Mask" "F.Paste")
			(net "M_B_CKE<3>")
		)
		(pad "L66" smd circle
			(at 20.080478 -21.950172)
			(size 0.4318 0.4318)
			(layers "F.Cu" "F.Mask" "F.Paste")
			(net "M_B_ECC<3>")
		)
		(pad "L68" smd circle
			(at 21.797518 -21.950172)
			(size 0.4318 0.4318)
			(layers "F.Cu" "F.Mask" "F.Paste")
			(net "M_B_DQS_DP<8>")
		)
		(pad "L70" smd circle
			(at 23.514558 -21.950172)
			(size 0.4318 0.4318)
			(layers "F.Cu" "F.Mask" "F.Paste")
			(net "M_B_ECC<4>")
		)
		(pad "L72" smd circle
			(at 25.231598 -21.950172)
			(size 0.4318 0.4318)
			(layers "F.Cu" "F.Mask" "F.Paste")
			(net "GND")
		)
		(pad "L74" smd circle
			(at 26.948384 -21.950172)
			(size 0.4318 0.4318)
			(layers "F.Cu" "F.Mask" "F.Paste")
			(net "M_A_DQ<30>")
		)
		(pad "L76" smd circle
			(at 28.665424 -21.950172)
			(size 0.4318 0.4318)
			(layers "F.Cu" "F.Mask" "F.Paste")
			(net "M_A_DQ<24>")
		)
		(pad "L78" smd circle
			(at 30.382464 -21.950172)
			(size 0.4318 0.4318)
			(layers "F.Cu" "F.Mask" "F.Paste")
			(net "GND")
		)
		(pad "L80" smd circle
			(at 32.099504 -21.950172)
			(size 0.4318 0.4318)
			(layers "F.Cu" "F.Mask" "F.Paste")
			(net "GND")
		)
		(pad "L82" smd circle
			(at 33.816544 -21.950172)
			(size 0.4318 0.4318)
			(layers "F.Cu" "F.Mask" "F.Paste")
			(net "GND")
		)
		(pad "L84" smd circle
			(at 35.533584 -21.950172)
			(size 0.4318 0.4318)
			(layers "F.Cu" "F.Mask" "F.Paste")
			(net "M_A_DQ<11>")
		)
	)
)
